(kicad_pcb
	(version 20260206)
	(generator "pcbnew")
	(generator_version "10.0")
	(general
		(thickness 1.6)
		(legacy_teardrops no)
	)
	(paper "A4")
	(title_block
		(title "pdpb — Lightning_PDPB_BRD.brd")
		(comment 1 "Lightning (Wiwynn / Facebook NVMe JBOF) / footprints 401-408 of 1140")
	)
	(layers
		(0 "F.Cu" signal "TOP")
		(4 "In1.Cu" signal "L2GND")
		(6 "In2.Cu" signal "L3")
		(8 "In3.Cu" signal "L4VCC")
		(10 "In4.Cu" signal "L5VCC")
		(12 "In5.Cu" signal "L6")
		(14 "In6.Cu" signal "L7GND")
		(2 "B.Cu" signal "BOTTOM")
		(9 "F.Adhes" user "F.Adhesive")
		(11 "B.Adhes" user "B.Adhesive")
		(13 "F.Paste" user "Package Geometry/Pastemask Top")
		(15 "B.Paste" user "Package Geometry/Pastemask Bottom")
		(5 "F.SilkS" user "Ref Des/Silkscreen Top")
		(7 "B.SilkS" user "Ref Des/Silkscreen Bottom")
		(1 "F.Mask" user "Board Geometry/Soldermask Top")
		(3 "B.Mask" user "Board Geometry/Soldermask Bottom")
		(17 "Dwgs.User" user "User.Drawings")
		(19 "Cmts.User" user "User.Comments")
		(21 "Eco1.User" user "User.Eco1")
		(23 "Eco2.User" user "User.Eco2")
		(25 "Edge.Cuts" user "Board Geometry/Outline")
		(27 "Margin" user)
		(31 "F.CrtYd" user "Package Geometry/Place Bound Top")
		(29 "B.CrtYd" user "Package Geometry/Place Bound Bottom")
		(35 "F.Fab" user "Ref Des/Assembly Top")
		(33 "B.Fab" user "Ref Des/Assembly Bottom")
	)
	(footprint ""
		(layer "F.Cu")
		(at 229.3112 -299.8724)
		(property "Reference" "R9243"
			(at 0 0 0)
			(layer "F.SilkS")
			(hide yes)
			(effects
				(font
					(size 1.27 1.27)
				)
			)
		)
		(property "Value" "2R2010F-GP"
			(at 0.0762 -4.5466 0)
			(unlocked yes)
			(layer "F.Fab")
			(hide yes)
			(effects
				(font
					(size 1.016 1.016)
					(thickness 0.1524)
				)
			)
		)
		(property "Device Type" "R2010H26"
			(at 0.0762 -6.1468 0)
			(unlocked yes)
			(layer "F.Fab")
			(hide yes)
			(effects
				(font
					(size 1.016 1.016)
					(thickness 0.1524)
				)
			)
		)
		(duplicate_pad_numbers_are_jumpers no)
		(fp_line
			(start -3.302 -1.651)
			(end -3.302 1.651)
			(stroke
				(width 0.1524)
				(type default)
			)
			(layer "F.SilkS")
		)
		(fp_line
			(start -3.302 1.651)
			(end 3.302 1.651)
			(stroke
				(width 0.1524)
				(type default)
			)
			(layer "F.SilkS")
		)
		(fp_line
			(start 3.302 -1.651)
			(end -3.302 -1.651)
			(stroke
				(width 0.1524)
				(type default)
			)
			(layer "F.SilkS")
		)
		(fp_line
			(start 3.302 1.651)
			(end 3.302 -1.651)
			(stroke
				(width 0.1524)
				(type default)
			)
			(layer "F.SilkS")
		)
		(fp_rect
			(start -3.3782 1.7272)
			(end 3.3782 -1.7272)
			(stroke
				(width 0)
				(type default)
			)
			(fill no)
			(layer "F.CrtYd")
		)
		(fp_poly
			(pts
				(xy 3.3782 -1.7272) (xy -3.3782 -1.7272) (xy -3.3782 1.7272) (xy 3.3782 1.7272)
			)
			(stroke
				(width 0)
				(type default)
			)
			(fill no)
			(layer "F.Fab")
		)
		(pad "1" smd rect
			(at -2.3495 0)
			(size 1.143 2.794)
			(layers "F.Cu" "F.Mask" "F.Paste")
			(net "P12V_SSD2")
		)
		(pad "2" smd rect
			(at 2.3495 0)
			(size 1.143 2.794)
			(layers "F.Cu" "F.Mask" "F.Paste")
			(net "12V_PRECH_SSD2")
		)
	)
	(footprint ""
		(layer "F.Cu")
		(at 96.52 -296.545)
		(property "Reference" "R9067"
			(at 0 0 0)
			(layer "F.SilkS")
			(hide yes)
			(effects
				(font
					(size 1.27 1.27)
				)
			)
		)
		(property "Value" "27R2F-GP"
			(at 0.064008 -3.993896 0)
			(unlocked yes)
			(layer "F.Fab")
			(hide yes)
			(effects
				(font
					(size 1.016 1.016)
					(thickness 0.1524)
				)
			)
		)
		(property "Device Type" "R402H16"
			(at 0.064008 -5.517896 0)
			(unlocked yes)
			(layer "F.Fab")
			(hide yes)
			(effects
				(font
					(size 1.016 1.016)
					(thickness 0.1524)
				)
			)
		)
		(duplicate_pad_numbers_are_jumpers no)
		(fp_line
			(start -0.508 -0.9398)
			(end -0.508 0.9398)
			(stroke
				(width 0.1524)
				(type default)
			)
			(layer "F.SilkS")
		)
		(fp_line
			(start 0.508 -0.9398)
			(end -0.508 -0.9398)
			(stroke
				(width 0.1524)
				(type default)
			)
			(layer "F.SilkS")
		)
		(fp_rect
			(start -0.508 0.9398)
			(end 0.508 -0.9398)
			(stroke
				(width 0)
				(type default)
			)
			(fill no)
			(layer "F.CrtYd")
		)
		(fp_rect
			(start -0.508 0.9398)
			(end 0.508 -0.9398)
			(stroke
				(width 0)
				(type default)
			)
			(fill no)
			(layer "F.Fab")
		)
		(pad "1" smd custom
			(at 0 -0.4445)
			(size 0.1397 0.1397)
			(layers "F.Cu" "F.Mask" "F.Paste")
			(net "PE_CLK_100M_DR2_2_R_N")
			(options
				(clearance outline)
				(anchor circle)
			)
			(primitives
				(gr_poly
					(pts
						(arc
							(start -0.1778 -0.2794)
							(mid -0.249642 -0.249642)
							(end -0.2794 -0.1778)
						)
						(arc
							(start -0.2794 0.1778)
							(mid -0.249642 0.249642)
							(end -0.1778 0.2794)
						)
						(arc
							(start 0.1778 0.2794)
							(mid 0.249642 0.249642)
							(end 0.2794 0.1778)
						)
						(arc
							(start 0.2794 -0.1778)
							(mid 0.249642 -0.249642)
							(end 0.1778 -0.2794)
						)
					)
					(width 0)
					(fill yes)
				)
			)
		)
		(pad "2" smd custom
			(at 0 0.4445)
			(size 0.1397 0.1397)
			(layers "F.Cu" "F.Mask" "F.Paste")
			(net "PE_CLK100M_DR2_2_N")
			(options
				(clearance outline)
				(anchor circle)
			)
			(primitives
				(gr_poly
					(pts
						(arc
							(start -0.1778 -0.2794)
							(mid -0.249642 -0.249642)
							(end -0.2794 -0.1778)
						)
						(arc
							(start -0.2794 0.1778)
							(mid -0.249642 0.249642)
							(end -0.1778 0.2794)
						)
						(arc
							(start 0.1778 0.2794)
							(mid 0.249642 0.249642)
							(end 0.2794 0.1778)
						)
						(arc
							(start 0.2794 -0.1778)
							(mid 0.249642 -0.249642)
							(end 0.1778 -0.2794)
						)
					)
					(width 0)
					(fill yes)
				)
			)
		)
	)
	(footprint ""
		(layer "F.Cu")
		(at 90.932 -17.526 180)
		(property "Reference" "R362"
			(at 0 0 180)
			(layer "F.SilkS")
			(hide yes)
			(effects
				(font
					(size 1.27 1.27)
				)
			)
		)
		(property "Value" "4K7R2F-GP"
			(at 0.064008 -3.993896 180)
			(unlocked yes)
			(layer "F.Fab")
			(hide yes)
			(effects
				(font
					(size 1.016 1.016)
					(thickness 0.1524)
				)
			)
		)
		(property "Device Type" "R402H16"
			(at 0.064008 -5.517896 180)
			(unlocked yes)
			(layer "F.Fab")
			(hide yes)
			(effects
				(font
					(size 1.016 1.016)
					(thickness 0.1524)
				)
			)
		)
		(duplicate_pad_numbers_are_jumpers no)
		(fp_line
			(start 0.508 -0.9398)
			(end -0.508 -0.9398)
			(stroke
				(width 0.1524)
				(type default)
			)
			(layer "F.SilkS")
		)
		(fp_line
			(start -0.508 -0.9398)
			(end -0.508 0.9398)
			(stroke
				(width 0.1524)
				(type default)
			)
			(layer "F.SilkS")
		)
		(fp_rect
			(start -0.508 0.9398)
			(end 0.508 -0.9398)
			(stroke
				(width 0)
				(type default)
			)
			(fill no)
			(layer "F.CrtYd")
		)
		(fp_rect
			(start -0.508 0.9398)
			(end 0.508 -0.9398)
			(stroke
				(width 0)
				(type default)
			)
			(fill no)
			(layer "F.Fab")
		)
		(pad "1" smd custom
			(at 0 -0.4445 180)
			(size 0.1397 0.1397)
			(layers "F.Cu" "F.Mask" "F.Paste")
			(net "P3V3")
			(options
				(clearance outline)
				(anchor circle)
			)
			(primitives
				(gr_poly
					(pts
						(arc
							(start -0.1778 -0.2794)
							(mid -0.249642 -0.249642)
							(end -0.2794 -0.1778)
						)
						(arc
							(start -0.2794 0.1778)
							(mid -0.249642 0.249642)
							(end -0.1778 0.2794)
						)
						(arc
							(start 0.1778 0.2794)
							(mid 0.249642 0.249642)
							(end 0.2794 0.1778)
						)
						(arc
							(start 0.2794 -0.1778)
							(mid 0.249642 -0.249642)
							(end 0.1778 -0.2794)
						)
					)
					(width 0)
					(fill yes)
				)
			)
		)
		(pad "2" smd custom
			(at 0 0.4445 180)
			(size 0.1397 0.1397)
			(layers "F.Cu" "F.Mask" "F.Paste")
			(net "VOL_SEN_ALERT")
			(options
				(clearance outline)
				(anchor circle)
			)
			(primitives
				(gr_poly
					(pts
						(arc
							(start -0.1778 -0.2794)
							(mid -0.249642 -0.249642)
							(end -0.2794 -0.1778)
						)
						(arc
							(start -0.2794 0.1778)
							(mid -0.249642 0.249642)
							(end -0.1778 0.2794)
						)
						(arc
							(start 0.1778 0.2794)
							(mid 0.249642 0.249642)
							(end 0.2794 0.1778)
						)
						(arc
							(start 0.2794 -0.1778)
							(mid 0.249642 -0.249642)
							(end 0.1778 -0.2794)
						)
					)
					(width 0)
					(fill yes)
				)
			)
		)
	)
	(footprint ""
		(layer "F.Cu")
		(at 14.224 -478.155)
		(property "Reference" "R406"
			(at 0 0 0)
			(layer "F.SilkS")
			(hide yes)
			(effects
				(font
					(size 1.27 1.27)
				)
			)
		)
		(property "Value" "10KR2F-2-GP"
			(at 0.064008 -3.993896 0)
			(unlocked yes)
			(layer "F.Fab")
			(hide yes)
			(effects
				(font
					(size 1.016 1.016)
					(thickness 0.1524)
				)
			)
		)
		(property "Device Type" "R402H16"
			(at 0.064008 -5.517896 0)
			(unlocked yes)
			(layer "F.Fab")
			(hide yes)
			(effects
				(font
					(size 1.016 1.016)
					(thickness 0.1524)
				)
			)
		)
		(duplicate_pad_numbers_are_jumpers no)
		(fp_line
			(start -0.508 -0.9398)
			(end -0.508 0.9398)
			(stroke
				(width 0.1524)
				(type default)
			)
			(layer "F.SilkS")
		)
		(fp_line
			(start 0.508 -0.9398)
			(end -0.508 -0.9398)
			(stroke
				(width 0.1524)
				(type default)
			)
			(layer "F.SilkS")
		)
		(fp_rect
			(start -0.508 0.9398)
			(end 0.508 -0.9398)
			(stroke
				(width 0)
				(type default)
			)
			(fill no)
			(layer "F.CrtYd")
		)
		(fp_rect
			(start -0.508 0.9398)
			(end 0.508 -0.9398)
			(stroke
				(width 0)
				(type default)
			)
			(fill no)
			(layer "F.Fab")
		)
		(pad "1" smd custom
			(at 0 -0.4445)
			(size 0.1397 0.1397)
			(layers "F.Cu" "F.Mask" "F.Paste")
			(net "P3V3")
			(options
				(clearance outline)
				(anchor circle)
			)
			(primitives
				(gr_poly
					(pts
						(arc
							(start -0.1778 -0.2794)
							(mid -0.249642 -0.249642)
							(end -0.2794 -0.1778)
						)
						(arc
							(start -0.2794 0.1778)
							(mid -0.249642 0.249642)
							(end -0.1778 0.2794)
						)
						(arc
							(start 0.1778 0.2794)
							(mid 0.249642 0.249642)
							(end 0.2794 0.1778)
						)
						(arc
							(start 0.2794 -0.1778)
							(mid 0.249642 -0.249642)
							(end 0.1778 -0.2794)
						)
					)
					(width 0)
					(fill yes)
				)
			)
		)
		(pad "2" smd custom
			(at 0 0.4445)
			(size 0.1397 0.1397)
			(layers "F.Cu" "F.Mask" "F.Paste")
			(net "DPB_HW_REVISION")
			(options
				(clearance outline)
				(anchor circle)
			)
			(primitives
				(gr_poly
					(pts
						(arc
							(start -0.1778 -0.2794)
							(mid -0.249642 -0.249642)
							(end -0.2794 -0.1778)
						)
						(arc
							(start -0.2794 0.1778)
							(mid -0.249642 0.249642)
							(end -0.1778 0.2794)
						)
						(arc
							(start 0.1778 0.2794)
							(mid 0.249642 0.249642)
							(end 0.2794 0.1778)
						)
						(arc
							(start 0.2794 -0.1778)
							(mid 0.249642 -0.249642)
							(end 0.1778 -0.2794)
						)
					)
					(width 0)
					(fill yes)
				)
			)
		)
	)
	(footprint ""
		(layer "F.Cu")
		(at 200.250806 -498.514878 180)
		(property "Reference" "R9777"
			(at 0 0 180)
			(layer "F.SilkS")
			(hide yes)
			(effects
				(font
					(size 1.27 1.27)
				)
			)
		)
		(property "Value" "47KR2J-2-GP"
			(at 0.064008 -3.993896 180)
			(unlocked yes)
			(layer "F.Fab")
			(hide yes)
			(effects
				(font
					(size 1.016 1.016)
					(thickness 0.1524)
				)
			)
		)
		(property "Device Type" "R402H16"
			(at 0.064008 -5.517896 180)
			(unlocked yes)
			(layer "F.Fab")
			(hide yes)
			(effects
				(font
					(size 1.016 1.016)
					(thickness 0.1524)
				)
			)
		)
		(duplicate_pad_numbers_are_jumpers no)
		(fp_line
			(start 0.508 -0.9398)
			(end -0.508 -0.9398)
			(stroke
				(width 0.1524)
				(type default)
			)
			(layer "F.SilkS")
		)
		(fp_line
			(start -0.508 -0.9398)
			(end -0.508 0.9398)
			(stroke
				(width 0.1524)
				(type default)
			)
			(layer "F.SilkS")
		)
		(fp_poly
			(pts
				(xy -0.508 0.9398) (xy 0.508 0.9398) (xy 0.508 -0.9398) (xy -0.508 -0.9398)
			)
			(stroke
				(width 0)
				(type default)
			)
			(fill no)
			(layer "F.CrtYd")
		)
		(fp_rect
			(start -0.508 0.9398)
			(end 0.508 -0.9398)
			(stroke
				(width 0)
				(type default)
			)
			(fill no)
			(layer "F.Fab")
		)
		(pad "1" smd custom
			(at 0 -0.4445 180)
			(size 0.1397 0.1397)
			(layers "F.Cu" "F.Mask" "F.Paste")
			(net "P12V")
			(options
				(clearance outline)
				(anchor circle)
			)
			(primitives
				(gr_poly
					(pts
						(arc
							(start -0.1778 -0.2794)
							(mid -0.249642 -0.249642)
							(end -0.2794 -0.1778)
						)
						(arc
							(start -0.2794 0.1778)
							(mid -0.249642 0.249642)
							(end -0.1778 0.2794)
						)
						(arc
							(start 0.1778 0.2794)
							(mid 0.249642 0.249642)
							(end 0.2794 0.1778)
						)
						(arc
							(start 0.2794 -0.1778)
							(mid 0.249642 -0.249642)
							(end 0.1778 -0.2794)
						)
					)
					(width 0)
					(fill yes)
				)
			)
		)
		(pad "2" smd custom
			(at 0 0.4445 180)
			(size 0.1397 0.1397)
			(layers "F.Cu" "F.Mask" "F.Paste")
			(net "P12V_MOST0_GATE")
			(options
				(clearance outline)
				(anchor circle)
			)
			(primitives
				(gr_poly
					(pts
						(arc
							(start -0.1778 -0.2794)
							(mid -0.249642 -0.249642)
							(end -0.2794 -0.1778)
						)
						(arc
							(start -0.2794 0.1778)
							(mid -0.249642 0.249642)
							(end -0.1778 0.2794)
						)
						(arc
							(start 0.1778 0.2794)
							(mid 0.249642 0.249642)
							(end 0.2794 0.1778)
						)
						(arc
							(start 0.2794 -0.1778)
							(mid 0.249642 -0.249642)
							(end 0.1778 -0.2794)
						)
					)
					(width 0)
					(fill yes)
				)
			)
		)
	)
	(footprint ""
		(layer "F.Cu")
		(at 25.4508 -208.7118)
		(property "Reference" "PC1250"
			(at 0 0 0)
			(layer "F.SilkS")
			(hide yes)
			(effects
				(font
					(size 1.27 1.27)
				)
			)
		)
		(property "Value" "SC22U25V6KX-GP-U"
			(at -2.860802 -5.279644 0)
			(unlocked yes)
			(layer "F.Fab")
			(hide yes)
			(effects
				(font
					(size 1.016 1.016)
					(thickness 0.1524)
				)
			)
		)
		(property "Device Type" "C1206-TO0D3H75"
			(at -2.860802 -6.803644 0)
			(unlocked yes)
			(layer "F.Fab")
			(hide yes)
			(effects
				(font
					(size 1.016 1.016)
					(thickness 0.1524)
				)
			)
		)
		(duplicate_pad_numbers_are_jumpers no)
		(fp_line
			(start -1.3081 -2.3749)
			(end 1.3081 -2.3749)
			(stroke
				(width 0.1524)
				(type default)
			)
			(layer "F.SilkS")
		)
		(fp_line
			(start -1.3081 2.3749)
			(end -1.3081 -2.3749)
			(stroke
				(width 0.1524)
				(type default)
			)
			(layer "F.SilkS")
		)
		(fp_line
			(start 1.3081 -2.3749)
			(end 1.3081 2.3749)
			(stroke
				(width 0.1524)
				(type default)
			)
			(layer "F.SilkS")
		)
		(fp_line
			(start 1.3081 2.3749)
			(end -1.3081 2.3749)
			(stroke
				(width 0.1524)
				(type default)
			)
			(layer "F.SilkS")
		)
		(fp_rect
			(start -0.8001 1.6002)
			(end 0.8001 -1.6002)
			(stroke
				(width 0)
				(type default)
			)
			(fill no)
			(layer "F.CrtYd")
		)
		(fp_poly
			(pts
				(xy -1.5621 2.4511) (xy -1.5621 1.6002) (xy 0.8001 1.6002) (xy 0.8001 -1.6002) (xy -0.8001 -1.6002)
				(xy -0.8001 1.5875) (xy -1.5621 1.5875) (xy -1.5621 -2.4511) (xy 1.5621 -2.4511) (xy 1.5621 2.4511)
			)
			(stroke
				(width 0)
				(type default)
			)
			(fill no)
			(layer "F.CrtYd")
		)
		(fp_rect
			(start -1.5621 2.4511)
			(end 1.5621 -2.4511)
			(stroke
				(width 0)
				(type default)
			)
			(fill no)
			(layer "F.Fab")
		)
		(pad "1" smd rect
			(at 0 -1.392936)
			(size 2.1082 1.4478)
			(layers "F.Cu" "F.Mask" "F.Paste")
			(net "P12V_SSD12")
		)
		(pad "2" smd rect
			(at 0 1.392936)
			(size 2.1082 1.4478)
			(layers "F.Cu" "F.Mask" "F.Paste")
			(net "GND")
		)
	)
	(footprint ""
		(layer "F.Cu")
		(at 37.0078 -85.9536)
		(property "Reference" "PC1198"
			(at 0 0 0)
			(layer "F.SilkS")
			(hide yes)
			(effects
				(font
					(size 1.27 1.27)
				)
			)
		)
		(property "Value" "SCD01U50V2KX-1GP"
			(at 1.1811 -2.7051 0)
			(unlocked yes)
			(layer "F.Fab")
			(hide yes)
			(effects
				(font
					(size 1.016 1.016)
					(thickness 0.1524)
				)
			)
		)
		(property "Device Type" "C402H22"
			(at 1.1811 -4.2291 0)
			(unlocked yes)
			(layer "F.Fab")
			(hide yes)
			(effects
				(font
					(size 1.016 1.016)
					(thickness 0.1524)
				)
			)
		)
		(duplicate_pad_numbers_are_jumpers no)
		(fp_rect
			(start -0.4318 0.9525)
			(end 0.4318 -0.9525)
			(stroke
				(width 0)
				(type default)
			)
			(fill no)
			(layer "F.CrtYd")
		)
		(fp_rect
			(start -0.4318 0.9525)
			(end 0.4318 -0.9525)
			(stroke
				(width 0)
				(type default)
			)
			(fill no)
			(layer "F.Fab")
		)
		(pad "1" smd custom
			(at 0 -0.4445)
			(size 0.1524 0.1524)
			(layers "F.Cu" "F.Mask" "F.Paste")
			(net "P12V_SSD9")
			(options
				(clearance outline)
				(anchor circle)
			)
			(primitives
				(gr_poly
					(pts
						(arc
							(start 0.3048 -0.2032)
							(mid 0.275042 -0.275042)
							(end 0.2032 -0.3048)
						)
						(arc
							(start -0.2032 -0.3048)
							(mid -0.275042 -0.275042)
							(end -0.3048 -0.2032)
						)
						(arc
							(start -0.3048 0.2032)
							(mid -0.275042 0.275042)
							(end -0.2032 0.3048)
						)
						(arc
							(start 0.2032 0.3048)
							(mid 0.275042 0.275042)
							(end 0.3048 0.2032)
						)
					)
					(width 0)
					(fill yes)
				)
			)
		)
		(pad "2" smd custom
			(at 0 0.4445)
			(size 0.1524 0.1524)
			(layers "F.Cu" "F.Mask" "F.Paste")
			(net "GND")
			(options
				(clearance outline)
				(anchor circle)
			)
			(primitives
				(gr_poly
					(pts
						(arc
							(start 0.3048 -0.2032)
							(mid 0.275042 -0.275042)
							(end 0.2032 -0.3048)
						)
						(arc
							(start -0.2032 -0.3048)
							(mid -0.275042 -0.275042)
							(end -0.3048 -0.2032)
						)
						(arc
							(start -0.3048 0.2032)
							(mid -0.275042 0.275042)
							(end -0.2032 0.3048)
						)
						(arc
							(start 0.2032 0.3048)
							(mid 0.275042 0.275042)
							(end 0.3048 0.2032)
						)
					)
					(width 0)
					(fill yes)
				)
			)
		)
	)
	(footprint ""
		(layer "F.Cu")
		(at 223.901 -431.292 180)
		(property "Reference" "PR9080"
			(at 0 0 180)
			(layer "F.SilkS")
			(hide yes)
			(effects
				(font
					(size 1.27 1.27)
				)
			)
		)
		(property "Value" "0R2J-2-GP"
			(at 0.064008 -3.993896 180)
			(unlocked yes)
			(layer "F.Fab")
			(hide yes)
			(effects
				(font
					(size 1.016 1.016)
					(thickness 0.1524)
				)
			)
		)
		(property "Device Type" "R402H16"
			(at 0.064008 -5.517896 180)
			(unlocked yes)
			(layer "F.Fab")
			(hide yes)
			(effects
				(font
					(size 1.016 1.016)
					(thickness 0.1524)
				)
			)
		)
		(duplicate_pad_numbers_are_jumpers no)
		(fp_line
			(start 0.508 -0.9398)
			(end -0.508 -0.9398)
			(stroke
				(width 0.1524)
				(type default)
			)
			(layer "F.SilkS")
		)
		(fp_line
			(start -0.508 -0.9398)
			(end -0.508 0.9398)
			(stroke
				(width 0.1524)
				(type default)
			)
			(layer "F.SilkS")
		)
		(fp_rect
			(start -0.508 0.9398)
			(end 0.508 -0.9398)
			(stroke
				(width 0)
				(type default)
			)
			(fill no)
			(layer "F.CrtYd")
		)
		(fp_rect
			(start -0.508 0.9398)
			(end 0.508 -0.9398)
			(stroke
				(width 0)
				(type default)
			)
			(fill no)
			(layer "F.Fab")
		)
		(pad "1" smd custom
			(at 0 -0.4445 180)
			(size 0.1397 0.1397)
			(layers "F.Cu" "F.Mask" "F.Paste")
			(net "P3V3_VBST_RR")
			(options
				(clearance outline)
				(anchor circle)
			)
			(primitives
				(gr_poly
					(pts
						(arc
							(start -0.1778 -0.2794)
							(mid -0.249642 -0.249642)
							(end -0.2794 -0.1778)
						)
						(arc
							(start -0.2794 0.1778)
							(mid -0.249642 0.249642)
							(end -0.1778 0.2794)
						)
						(arc
							(start 0.1778 0.2794)
							(mid 0.249642 0.249642)
							(end 0.2794 0.1778)
						)
						(arc
							(start 0.2794 -0.1778)
							(mid 0.249642 -0.249642)
							(end 0.1778 -0.2794)
						)
					)
					(width 0)
					(fill yes)
				)
			)
		)
		(pad "2" smd custom
			(at 0 0.4445 180)
			(size 0.1397 0.1397)
			(layers "F.Cu" "F.Mask" "F.Paste")
			(net "P3V3_VBST")
			(options
				(clearance outline)
				(anchor circle)
			)
			(primitives
				(gr_poly
					(pts
						(arc
							(start -0.1778 -0.2794)
							(mid -0.249642 -0.249642)
							(end -0.2794 -0.1778)
						)
						(arc
							(start -0.2794 0.1778)
							(mid -0.249642 0.249642)
							(end -0.1778 0.2794)
						)
						(arc
							(start 0.1778 0.2794)
							(mid 0.249642 0.249642)
							(end 0.2794 0.1778)
						)
						(arc
							(start 0.2794 -0.1778)
							(mid 0.249642 -0.249642)
							(end 0.1778 -0.2794)
						)
					)
					(width 0)
					(fill yes)
				)
			)
		)
	)
)
